(kicad_pcb
	(version 20241229)
	(generator "pcbnew")
	(generator_version "9.0")
	(general
		(thickness 1.62)
		(legacy_teardrops no)
	)
	(paper "A4")
	(title_block
		(title "OCuLink to 10GbE adapter")
		(date "2026-02-23")
		(rev "1.1.0")
		(company "Antmicro Ltd")
		(comment 1 "www.antmicro.com")
		(comment 9 "footprints 13-17 of 510")
	)
	(layers
		(0 "F.Cu" signal)
		(4 "In1.Cu" signal)
		(6 "In2.Cu" signal)
		(8 "In3.Cu" signal)
		(10 "In4.Cu" signal)
		(12 "In5.Cu" signal)
		(14 "In6.Cu" signal)
		(2 "B.Cu" signal)
		(9 "F.Adhes" user "F.Adhesive")
		(11 "B.Adhes" user "B.Adhesive")
		(13 "F.Paste" user)
		(15 "B.Paste" user)
		(5 "F.SilkS" user "F.Silkscreen")
		(7 "B.SilkS" user "B.Silkscreen")
		(1 "F.Mask" user)
		(3 "B.Mask" user)
		(17 "Dwgs.User" user "User.Drawings")
		(19 "Cmts.User" user "User.Comments")
		(21 "Eco1.User" user "User.Eco1")
		(23 "Eco2.User" user "User.Eco2")
		(25 "Edge.Cuts" user)
		(27 "Margin" user)
		(31 "F.CrtYd" user "F.Courtyard")
		(29 "B.CrtYd" user "B.Courtyard")
		(35 "F.Fab" user)
		(33 "B.Fab" user)
	)
	(footprint "antmicro-footprints:Vishay_PowerPAK_1212-8_Single"
		(layer "F.Cu")
		(at 82.9 66 90)
		(descr "PowerPAK 1212-8 Single")
		(tags "Vishay PowerPAK 1212-8 Single")
		(property "Reference" "Q3"
			(at -1.95 -1.9 90)
			(layer "F.SilkS")
			(effects
				(font
					(size 0.7 0.7)
					(thickness 0.15)
				)
				(justify left bottom)
			)
		)
		(property "Value" "SQS401EN-T1_BE3"
			(at 0 2.7 90)
			(layer "F.Fab")
			(hide yes)
			(effects
				(font
					(size 0.7 0.7)
					(thickness 0.15)
				)
				(justify left bottom)
			)
		)
		(property "Datasheet" "https://www.vishay.com/docs/65529/sqs401en.pdf"
			(at 0 0 90)
			(layer "F.Fab")
			(hide yes)
			(effects
				(font
					(size 1.27 1.27)
					(thickness 0.15)
				)
			)
		)
		(property "Description" "MOSFET, P Channel, 40 V, 16A, 0.047 ohm, PowerPAK 1212-8, Surface Mount"
			(at 0 0 90)
			(layer "F.Fab")
			(hide yes)
			(effects
				(font
					(size 1.27 1.27)
					(thickness 0.15)
				)
			)
		)
		(property "MPN" "SQS401EN-T1_BE3"
			(at 0 0 90)
			(unlocked yes)
			(layer "F.Fab")
			(hide yes)
			(effects
				(font
					(size 1 1)
					(thickness 0.15)
				)
			)
		)
		(property "Manufacturer" "Vishay"
			(at 0 0 90)
			(unlocked yes)
			(layer "F.Fab")
			(hide yes)
			(effects
				(font
					(size 1 1)
					(thickness 0.15)
				)
			)
		)
		(property "Author" "Antmicro"
			(at 0 0 90)
			(unlocked yes)
			(layer "F.Fab")
			(hide yes)
			(effects
				(font
					(size 1 1)
					(thickness 0.15)
				)
			)
		)
		(property "License" "Apache-2.0"
			(at 0 0 90)
			(unlocked yes)
			(layer "F.Fab")
			(hide yes)
			(effects
				(font
					(size 1 1)
					(thickness 0.15)
				)
			)
		)
		(sheetname "/Power/Ideal diode 2/")
		(sheetfile "ideal-diode.kicad_sch")
		(attr smd)
		(fp_line
			(start 1.648 -1.651)
			(end 1.648 -1.317)
			(stroke
				(width 0.15)
				(type solid)
			)
			(layer "F.SilkS")
		)
		(fp_line
			(start -1.651 -1.651)
			(end 1.648 -1.651)
			(stroke
				(width 0.15)
				(type solid)
			)
			(layer "F.SilkS")
		)
		(fp_line
			(start -1.651 -1.651)
			(end -1.651 -1.317)
			(stroke
				(width 0.15)
				(type solid)
			)
			(layer "F.SilkS")
		)
		(fp_line
			(start 1.634 1.3)
			(end 1.634 1.634)
			(stroke
				(width 0.15)
				(type solid)
			)
			(layer "F.SilkS")
		)
		(fp_line
			(start -1.635 1.3)
			(end -1.635 1.634)
			(stroke
				(width 0.15)
				(type solid)
			)
			(layer "F.SilkS")
		)
		(fp_line
			(start -1.635 1.634)
			(end 1.634 1.634)
			(stroke
				(width 0.15)
				(type solid)
			)
			(layer "F.SilkS")
		)
		(fp_circle
			(center -1.9 -1.4)
			(end -1.85 -1.4)
			(stroke
				(width 0.15)
				(type solid)
			)
			(fill yes)
			(layer "F.SilkS")
		)
		(fp_rect
			(start -2 -1.8)
			(end 2 1.798)
			(stroke
				(width 0.05)
				(type solid)
			)
			(fill no)
			(layer "F.CrtYd")
		)
		(fp_line
			(start -1.6425 -1.4175)
			(end -1.4175 -1.6425)
			(stroke
				(width 0.15)
				(type solid)
			)
			(layer "F.Fab")
		)
		(fp_rect
			(start -1.651 -1.651)
			(end 1.648 1.648)
			(stroke
				(width 0.15)
				(type solid)
			)
			(fill no)
			(layer "F.Fab")
		)
		(pad "1" smd rect
			(at -1.436 -0.99 90)
			(size 0.99 0.405)
			(layers "F.Cu" "F.Mask" "F.Paste")
			(net 314 "VCC")
			(pinfunction "S")
			(pintype "passive")
		)
		(pad "2" smd rect
			(at -1.436 -0.332 90)
			(size 0.99 0.405)
			(layers "F.Cu" "F.Mask" "F.Paste")
			(net 314 "VCC")
			(pinfunction "S")
			(pintype "passive")
		)
		(pad "3" smd rect
			(at -1.436 0.33 90)
			(size 0.99 0.405)
			(layers "F.Cu" "F.Mask" "F.Paste")
			(net 314 "VCC")
			(pinfunction "S")
			(pintype "passive")
		)
		(pad "4" smd rect
			(at -1.436 0.988 90)
			(size 0.99 0.405)
			(layers "F.Cu" "F.Mask" "F.Paste")
			(net 156 "Net-(Q3-G)")
			(pinfunction "G")
			(pintype "passive")
		)
		(pad "5" smd custom
			(at 0.557 0 90)
			(size 1.725 2.235)
			(layers "F.Cu" "F.Mask" "F.Paste")
			(net 351 "/Power/+5V_USB")
			(pinfunction "D")
			(pintype "passive")
			(zone_connect 2)
			(options
				(clearance outline)
				(anchor rect)
			)
			(primitives
				(gr_poly
					(pts
						(xy 0.8625 0.1275) (xy 0.8625 -0.1275) (xy 1.3725 -0.1275) (xy 1.3725 -0.5325) (xy 0.8625 -0.5325)
						(xy 0.8625 -0.7875) (xy 1.3725 -0.7875) (xy 1.3725 -1.195) (xy 0.6125 -1.195) (xy 0.6125 1.195)
						(xy 1.3725 1.195) (xy 1.3725 0.7875) (xy 0.8625 0.7875) (xy 0.8625 0.5325) (xy 1.3725 0.5325)
						(xy 1.3725 0.1275)
					)
					(width 0)
					(fill yes)
				)
			)
		)
	)
	(footprint "antmicro-footprints:R_0402_1005Metric"
		(layer "F.Cu")
		(at 110.15 106.55 -90)
		(descr "Resistor SMD 0402")
		(tags "resistor SMD 0402")
		(property "Reference" "R177"
			(at 0.1 2.55 90)
			(layer "F.SilkS")
			(effects
				(font
					(size 0.7 0.7)
					(thickness 0.15)
				)
				(justify left bottom)
			)
		)
		(property "Value" "R_0R_0402"
			(at -1.011843 1.772046 90)
			(layer "F.Fab")
			(hide yes)
			(effects
				(font
					(size 0.7 0.7)
					(thickness 0.15)
				)
				(justify right top)
			)
		)
		(property "Datasheet" "https://industrial.panasonic.com/cdbs/www-data/pdf/RDA0000/AOA0000C301.pdf"
			(at 0 0 90)
			(layer "F.Fab")
			(hide yes)
			(effects
				(font
					(size 1.27 1.27)
					(thickness 0.15)
				)
			)
		)
		(property "Description" "SMD Chip Resistor, Jumper, 0 ohm, 100 mW, 0402 [1005 Metric], Thick Film, General Purpose"
			(at 0 0 90)
			(layer "F.Fab")
			(hide yes)
			(effects
				(font
					(size 1.27 1.27)
					(thickness 0.15)
				)
			)
		)
		(property "MPN" "ERJ2GE0R00X"
			(at 0 0 270)
			(unlocked yes)
			(layer "F.Fab")
			(hide yes)
			(effects
				(font
					(size 1 1)
					(thickness 0.15)
				)
			)
		)
		(property "Manufacturer" "Panasonic"
			(at 0 0 270)
			(unlocked yes)
			(layer "F.Fab")
			(hide yes)
			(effects
				(font
					(size 1 1)
					(thickness 0.15)
				)
			)
		)
		(property "License" "Apache-2.0"
			(at 0 0 270)
			(unlocked yes)
			(layer "F.Fab")
			(hide yes)
			(effects
				(font
					(size 1 1)
					(thickness 0.15)
				)
			)
		)
		(property "Author" "Antmicro"
			(at 0 0 270)
			(unlocked yes)
			(layer "F.Fab")
			(hide yes)
			(effects
				(font
					(size 1 1)
					(thickness 0.15)
				)
			)
		)
		(property "Val" "0R"
			(at 0 0 270)
			(unlocked yes)
			(layer "F.Fab")
			(hide yes)
			(effects
				(font
					(size 1 1)
					(thickness 0.15)
				)
			)
		)
		(property "Tolerance" "~"
			(at 0 0 270)
			(unlocked yes)
			(layer "F.Fab")
			(hide yes)
			(effects
				(font
					(size 1 1)
					(thickness 0.15)
				)
			)
		)
		(property "Current" "1A"
			(at 0 0 270)
			(unlocked yes)
			(layer "F.Fab")
			(hide yes)
			(effects
				(font
					(size 1 1)
					(thickness 0.15)
				)
			)
		)
		(sheetname "/Fan controller/")
		(sheetfile "fan-controller.kicad_sch")
		(attr smd exclude_from_pos_files exclude_from_bom dnp)
		(fp_rect
			(start -0.925 -0.47)
			(end 0.925 0.47)
			(stroke
				(width 0.05)
				(type default)
			)
			(fill no)
			(layer "F.CrtYd")
		)
		(fp_rect
			(start -0.5 -0.25)
			(end 0.5 0.25)
			(stroke
				(width 0.15)
				(type solid)
			)
			(fill no)
			(layer "F.Fab")
		)
		(pad "1" smd roundrect
			(at -0.48 0 270)
			(size 0.59 0.64)
			(layers "F.Cu" "F.Mask" "F.Paste")
			(roundrect_rratio 0.25)
			(net 398 "/Fan controller/D0")
			(pintype "passive")
		)
		(pad "2" smd roundrect
			(at 0.48 0 270)
			(size 0.59 0.64)
			(layers "F.Cu" "F.Mask" "F.Paste")
			(roundrect_rratio 0.25)
			(net 388 "/Fan controller/+5V")
			(pintype "passive")
		)
	)
	(footprint "antmicro-footprints:R_0402_1005Metric"
		(layer "F.Cu")
		(at 101.3 104.25)
		(descr "Resistor SMD 0402")
		(tags "resistor SMD 0402")
		(property "Reference" "R89"
			(at -0.8 15.175 0)
			(layer "F.SilkS")
			(effects
				(font
					(size 0.7 0.7)
					(thickness 0.15)
				)
				(justify left bottom)
			)
		)
		(property "Value" "R_100k_0402"
			(at -1.011843 1.772046 0)
			(layer "F.Fab")
			(hide yes)
			(effects
				(font
					(size 0.7 0.7)
					(thickness 0.15)
				)
				(justify left bottom)
			)
		)
		(property "Datasheet" "https://www.bourns.com/docs/product-datasheets/cr.pdf"
			(at 0 0 0)
			(layer "F.Fab")
			(hide yes)
			(effects
				(font
					(size 1.27 1.27)
					(thickness 0.15)
				)
			)
		)
		(property "Description" "SMD Chip Resistor, 100 kohm, ± 1%, 62.5 mW, 0402 [1005 Metric], Thick Film, General Purpose"
			(at 0 0 0)
			(layer "F.Fab")
			(hide yes)
			(effects
				(font
					(size 1.27 1.27)
					(thickness 0.15)
				)
			)
		)
		(property "MPN" "CR0402-FX-1003GLF"
			(at 0 0 0)
			(unlocked yes)
			(layer "F.Fab")
			(hide yes)
			(effects
				(font
					(size 1 1)
					(thickness 0.15)
				)
			)
		)
		(property "Manufacturer" "Bourns"
			(at 0 0 0)
			(unlocked yes)
			(layer "F.Fab")
			(hide yes)
			(effects
				(font
					(size 1 1)
					(thickness 0.15)
				)
			)
		)
		(property "License" "Apache-2.0"
			(at 0 0 0)
			(unlocked yes)
			(layer "F.Fab")
			(hide yes)
			(effects
				(font
					(size 1 1)
					(thickness 0.15)
				)
			)
		)
		(property "Author" "Antmicro"
			(at 0 0 0)
			(unlocked yes)
			(layer "F.Fab")
			(hide yes)
			(effects
				(font
					(size 1 1)
					(thickness 0.15)
				)
			)
		)
		(property "Val" "100k"
			(at 0 0 0)
			(unlocked yes)
			(layer "F.Fab")
			(hide yes)
			(effects
				(font
					(size 1 1)
					(thickness 0.15)
				)
			)
		)
		(property "Tolerance" "1%"
			(at 0 0 0)
			(unlocked yes)
			(layer "F.Fab")
			(hide yes)
			(effects
				(font
					(size 1 1)
					(thickness 0.15)
				)
			)
		)
		(sheetname "/X710-AT2 Misc/")
		(sheetfile "x710-at2-mics.kicad_sch")
		(attr smd)
		(fp_rect
			(start -0.925 -0.47)
			(end 0.925 0.47)
			(stroke
				(width 0.05)
				(type default)
			)
			(fill no)
			(layer "F.CrtYd")
		)
		(fp_rect
			(start -0.5 -0.25)
			(end 0.5 0.25)
			(stroke
				(width 0.15)
				(type solid)
			)
			(fill no)
			(layer "F.Fab")
		)
		(pad "1" smd roundrect
			(at -0.48 0)
			(size 0.59 0.64)
			(layers "F.Cu" "F.Mask" "F.Paste")
			(roundrect_rratio 0.25)
			(net 28 "GND")
			(pintype "passive")
		)
		(pad "2" smd roundrect
			(at 0.48 0)
			(size 0.59 0.64)
			(layers "F.Cu" "F.Mask" "F.Paste")
			(roundrect_rratio 0.25)
			(net 367 "/X710-AT2 Misc/NCSI.REF_CLK")
			(pintype "passive")
		)
	)
	(footprint "antmicro-footprints:C_0603_1608Metric_EIA"
		(layer "F.Cu")
		(at 51.9 111.6 -90)
		(descr "Capacitor SMD 0603, IPC-7351 Density Level A")
		(tags "Capacitor 0603")
		(property "Reference" "C30"
			(at 1.01 0.47 90)
			(layer "F.SilkS")
			(effects
				(font
					(size 0.7 0.7)
					(thickness 0.15)
				)
				(justify right top)
			)
		)
		(property "Value" "C_22u_16V_0603"
			(at -1.42757 1.770288 90)
			(layer "F.Fab")
			(hide yes)
			(effects
				(font
					(size 0.7 0.7)
					(thickness 0.15)
				)
				(justify right top)
			)
		)
		(property "Datasheet" "https://product.samsungsem.com/mlcc/CL10A226MO7JZN.do"
			(at 0 0 90)
			(layer "F.Fab")
			(hide yes)
			(effects
				(font
					(size 1.27 1.27)
					(thickness 0.15)
				)
			)
		)
		(property "Description" "SMD Multilayer Ceramic Capacitor"
			(at 0 0 90)
			(layer "F.Fab")
			(hide yes)
			(effects
				(font
					(size 1.27 1.27)
					(thickness 0.15)
				)
			)
		)
		(property "MPN" "CL10A226MO7JZNC"
			(at 0 0 270)
			(unlocked yes)
			(layer "F.Fab")
			(hide yes)
			(effects
				(font
					(size 1 1)
					(thickness 0.15)
				)
			)
		)
		(property "Manufacturer" "Samsung Electro-Mechanics"
			(at 0 0 270)
			(unlocked yes)
			(layer "F.Fab")
			(hide yes)
			(effects
				(font
					(size 1 1)
					(thickness 0.15)
				)
			)
		)
		(property "License" "Apache-2.0"
			(at 0 0 270)
			(unlocked yes)
			(layer "F.Fab")
			(hide yes)
			(effects
				(font
					(size 1 1)
					(thickness 0.15)
				)
			)
		)
		(property "Author" "Antmicro"
			(at 0 0 270)
			(unlocked yes)
			(layer "F.Fab")
			(hide yes)
			(effects
				(font
					(size 1 1)
					(thickness 0.15)
				)
			)
		)
		(property "Val" "22u"
			(at 0 0 270)
			(unlocked yes)
			(layer "F.Fab")
			(hide yes)
			(effects
				(font
					(size 1 1)
					(thickness 0.15)
				)
			)
		)
		(property "Voltage" "16V"
			(at 0 0 270)
			(unlocked yes)
			(layer "F.Fab")
			(hide yes)
			(effects
				(font
					(size 1 1)
					(thickness 0.15)
				)
			)
		)
		(property "Dielectric" ""
			(at 0 0 270)
			(unlocked yes)
			(layer "F.Fab")
			(hide yes)
			(effects
				(font
					(size 1 1)
					(thickness 0.15)
				)
			)
		)
		(property "Public" "False"
			(at 0 0 270)
			(unlocked yes)
			(layer "F.Fab")
			(hide yes)
			(effects
				(font
					(size 1 1)
					(thickness 0.15)
				)
			)
		)
		(sheetname "/Power/")
		(sheetfile "power.kicad_sch")
		(attr smd)
		(fp_line
			(start -0.15 0.55)
			(end 0.15 0.55)
			(stroke
				(width 0.15)
				(type solid)
			)
			(layer "F.SilkS")
		)
		(fp_line
			(start -0.15 -0.55)
			(end 0.15 -0.55)
			(stroke
				(width 0.15)
				(type solid)
			)
			(layer "F.SilkS")
		)
		(fp_rect
			(start -1.25 -0.65)
			(end 1.25 0.65)
			(stroke
				(width 0.05)
				(type solid)
			)
			(fill no)
			(layer "F.CrtYd")
		)
		(fp_rect
			(start -0.8 -0.45)
			(end 0.8 0.45)
			(stroke
				(width 0.15)
				(type solid)
			)
			(fill no)
			(layer "F.Fab")
		)
		(pad "1" smd roundrect
			(at -0.7 0 270)
			(size 0.8 1.1)
			(layers "F.Cu" "F.Mask" "F.Paste")
			(roundrect_rratio 0.2)
			(net 28 "GND")
			(pintype "passive")
		)
		(pad "2" smd roundrect
			(at 0.7 0 270)
			(size 0.8 1.1)
			(layers "F.Cu" "F.Mask" "F.Paste")
			(roundrect_rratio 0.2)
			(net 314 "VCC")
			(pintype "passive")
		)
	)
	(footprint "antmicro-footprints:SOD-123FL"
		(layer "F.Cu")
		(at 68.1 62.02)
		(property "Reference" "D1"
			(at 2.38 0.35 0)
			(layer "F.SilkS")
			(effects
				(font
					(size 0.7 0.7)
					(thickness 0.15)
				)
				(justify left bottom)
			)
		)
		(property "Value" "SZSMF4L14AT3G"
			(at 0 1.967 0)
			(layer "F.Fab")
			(hide yes)
			(effects
				(font
					(size 0.7 0.7)
					(thickness 0.15)
				)
				(justify left bottom)
			)
		)
		(property "Datasheet" "https://www.mouser.com/datasheet/2/240/media-3320461.pdf"
			(at 0 0 0)
			(layer "F.Fab")
			(hide yes)
			(effects
				(font
					(size 1.27 1.27)
					(thickness 0.15)
				)
			)
		)
		(property "Description" "ESD, TVS Diode, 14V, UNI, 400W, SOD-123FL"
			(at 0 0 0)
			(layer "F.Fab")
			(hide yes)
			(effects
				(font
					(size 1.27 1.27)
					(thickness 0.15)
				)
			)
		)
		(property "MPN" "SZSMF4L12AT3G"
			(at 0 0 0)
			(unlocked yes)
			(layer "F.Fab")
			(hide yes)
			(effects
				(font
					(size 1 1)
					(thickness 0.15)
				)
			)
		)
		(property "Author" "Antmicro"
			(at 0 0 0)
			(unlocked yes)
			(layer "F.Fab")
			(hide yes)
			(effects
				(font
					(size 1 1)
					(thickness 0.15)
				)
			)
		)
		(property "License" "Apache-2.0"
			(at 0 0 0)
			(unlocked yes)
			(layer "F.Fab")
			(hide yes)
			(effects
				(font
					(size 1 1)
					(thickness 0.15)
				)
			)
		)
		(property "Manufacturer" "Littelfuse"
			(at 0 0 0)
			(unlocked yes)
			(layer "F.Fab")
			(hide yes)
			(effects
				(font
					(size 1 1)
					(thickness 0.15)
				)
			)
		)
		(sheetname "/Power/")
		(sheetfile "power.kicad_sch")
		(attr smd)
		(fp_line
			(start -2.3 -1.1)
			(end -2.3 1.1)
			(stroke
				(width 0.15)
				(type solid)
			)
			(layer "F.SilkS")
		)
		(fp_line
			(start -2.3 1.1)
			(end 0 1.1)
			(stroke
				(width 0.15)
				(type solid)
			)
			(layer "F.SilkS")
		)
		(fp_line
			(start 0 -1.1)
			(end -2.3 -1.1)
			(stroke
				(width 0.15)
				(type solid)
			)
			(layer "F.SilkS")
		)
		(fp_rect
			(start -2.35 -1.125)
			(end 2.35 1.125)
			(stroke
				(width 0.05)
				(type solid)
			)
			(fill no)
			(layer "F.CrtYd")
		)
		(fp_rect
			(start -1.825 -0.875)
			(end 1.824 0.873)
			(stroke
				(width 0.15)
				(type solid)
			)
			(fill no)
			(layer "F.Fab")
		)
		(fp_rect
			(start -0.775 -0.875)
			(end -0.525 0.875)
			(stroke
				(width 0.15)
				(type solid)
			)
			(fill yes)
			(layer "F.Fab")
		)
		(pad "1" smd roundrect
			(at -1.43 0)
			(size 1.34 1.8)
			(layers "F.Cu" "F.Mask" "F.Paste")
			(roundrect_rratio 0.14)
			(net 350 "/Power/+12V_IN")
			(pinfunction "C")
			(pintype "passive")
		)
		(pad "2" smd roundrect
			(at 1.429 0)
			(size 1.34 1.8)
			(layers "F.Cu" "F.Mask" "F.Paste")
			(roundrect_rratio 0.14)
			(net 28 "GND")
			(pinfunction "A")
			(pintype "passive")
		)
	)
)
